(kicad_pcb
	(version 20260206)
	(generator "pcbnew")
	(generator_version "10.0")
	(general
		(thickness 1.6)
		(legacy_teardrops no)
	)
	(paper "A4")
	(title_block
		(title "Wiwynn_Tioga_Pass_MB.brd")
		(comment 1 "Tioga Pass / footprints 2084-2091 of 4770")
	)
	(layers
		(0 "F.Cu" signal "TOP")
		(4 "In1.Cu" signal "L2GND")
		(6 "In2.Cu" signal "L3")
		(8 "In3.Cu" signal "L4GND")
		(10 "In4.Cu" signal "L5")
		(12 "In5.Cu" signal "L6GND")
		(14 "In6.Cu" signal "L7VCC")
		(16 "In7.Cu" signal "L8VCC")
		(18 "In8.Cu" signal "L9GND")
		(20 "In9.Cu" signal "L10")
		(22 "In10.Cu" signal "L11GND")
		(24 "In11.Cu" signal "L12")
		(26 "In12.Cu" signal "L13GND")
		(2 "B.Cu" signal "BOTTOM")
		(9 "F.Adhes" user "F.Adhesive")
		(11 "B.Adhes" user "B.Adhesive")
		(13 "F.Paste" user "Package Geometry/Pastemask Top")
		(15 "B.Paste" user "Package Geometry/Pastemask Bottom")
		(5 "F.SilkS" user "Ref Des/Silkscreen Top")
		(7 "B.SilkS" user "Ref Des/Silkscreen Bottom")
		(1 "F.Mask" user "Board Geometry/Soldermask Top")
		(3 "B.Mask" user "Board Geometry/Soldermask Bottom")
		(17 "Dwgs.User" user "User.Drawings")
		(19 "Cmts.User" user "User.Comments")
		(21 "Eco1.User" user "User.Eco1")
		(23 "Eco2.User" user "User.Eco2")
		(25 "Edge.Cuts" user "Board Geometry/Outline")
		(27 "Margin" user)
		(31 "F.CrtYd" user "Package Geometry/Place Bound Top")
		(29 "B.CrtYd" user "Package Geometry/Place Bound Bottom")
		(35 "F.Fab" user "Ref Des/Assembly Top")
		(33 "B.Fab" user "Ref Des/Assembly Bottom")
	)
	(footprint ""
		(layer "F.Cu")
		(at 106.89844 -73.279)
		(property "Reference" "C3D21"
			(at 0 0 0)
			(layer "F.SilkS")
			(hide yes)
			(effects
				(font
					(size 1.27 1.27)
				)
			)
		)
		(property "Value" ""
			(at 0 0 0)
			(layer "F.Fab")
			(effects
				(font
					(size 1.27 1.27)
				)
			)
		)
		(duplicate_pad_numbers_are_jumpers no)
		(fp_poly
			(pts
				(xy -0.4953 -0.2032) (xy 0.4953 -0.2032) (xy 0.4953 1.6002) (xy -0.4953 1.6002)
			)
			(stroke
				(width 0)
				(type default)
			)
			(fill no)
			(layer "F.CrtYd")
		)
		(fp_line
			(start -0.4953 -0.2032)
			(end 0.4953 -0.2032)
			(stroke
				(width 0.1)
				(type default)
			)
			(layer "F.Fab")
		)
		(fp_line
			(start -0.4953 1.6002)
			(end -0.4953 -0.2032)
			(stroke
				(width 0.1)
				(type default)
			)
			(layer "F.Fab")
		)
		(fp_line
			(start 0.4953 -0.2032)
			(end 0.4953 1.6002)
			(stroke
				(width 0.1)
				(type default)
			)
			(layer "F.Fab")
		)
		(fp_line
			(start 0.4953 1.6002)
			(end -0.4953 1.6002)
			(stroke
				(width 0.1)
				(type default)
			)
			(layer "F.Fab")
		)
		(pad "1" smd rect
			(at 0 0)
			(size 0.762 0.889)
			(layers "F.Cu" "F.Mask" "F.Paste")
			(net "PVCCMCP_CPU1")
		)
		(pad "2" smd rect
			(at 0 1.397)
			(size 0.762 0.889)
			(layers "F.Cu" "F.Mask" "F.Paste")
			(net "GND")
		)
		(zone
			(layer "F.Cu")
			(hatch none 0.5)
			(connect_pads
				(clearance 0)
			)
			(min_thickness 0.25)
			(keepout
				(tracks not_allowed)
				(vias allowed)
				(pads allowed)
				(copperpour not_allowed)
				(footprints allowed)
			)
			(placement
				(enabled no)
				(sheetname "")
			)
			(fill
				(thermal_gap 0.5)
				(thermal_bridge_width 0.5)
				(island_removal_mode 0)
			)
			(polygon
				(pts
					(xy 106.51744 -72.8345) (xy 107.27944 -72.8345) (xy 107.27944 -72.3265) (xy 106.51744 -72.3265)
				)
			)
		)
	)
	(footprint ""
		(layer "F.Cu")
		(at 27.559 -57.785 90)
		(property "Reference" "RT15"
			(at 1.01473 0.656336 0)
			(unlocked yes)
			(layer "F.SilkS")
			(effects
				(font
					(size 0.4064 0.254)
					(thickness 0.1524)
				)
			)
		)
		(property "Value" ""
			(at 0 0 90)
			(layer "F.Fab")
			(effects
				(font
					(size 1.27 1.27)
				)
			)
		)
		(duplicate_pad_numbers_are_jumpers no)
		(fp_poly
			(pts
				(xy -0.4953 -0.2032) (xy 0.4953 -0.2032) (xy 0.4953 1.6002) (xy -0.4953 1.6002)
			)
			(stroke
				(width 0)
				(type default)
			)
			(fill no)
			(layer "F.CrtYd")
		)
		(fp_line
			(start 0.4953 -0.2032)
			(end 0.4953 1.6002)
			(stroke
				(width 0.1)
				(type default)
			)
			(layer "F.Fab")
		)
		(fp_line
			(start -0.4953 -0.2032)
			(end 0.4953 -0.2032)
			(stroke
				(width 0.1)
				(type default)
			)
			(layer "F.Fab")
		)
		(fp_line
			(start 0.4953 1.6002)
			(end -0.4953 1.6002)
			(stroke
				(width 0.1)
				(type default)
			)
			(layer "F.Fab")
		)
		(fp_line
			(start -0.4953 1.6002)
			(end -0.4953 -0.2032)
			(stroke
				(width 0.1)
				(type default)
			)
			(layer "F.Fab")
		)
		(pad "1" smd rect
			(at 0 0 90)
			(size 0.762 0.889)
			(layers "F.Cu" "F.Mask" "F.Paste")
			(net "VR_PVCCIN_CPU1_PH1_BOOT")
		)
		(pad "2" smd rect
			(at 0 1.397 90)
			(size 0.762 0.889)
			(layers "F.Cu" "F.Mask" "F.Paste")
			(net "VR_PVCCIN_CPU1_PH1_BOOT_R")
		)
		(zone
			(layer "F.Cu")
			(hatch none 0.5)
			(connect_pads
				(clearance 0)
			)
			(min_thickness 0.25)
			(keepout
				(tracks allowed)
				(vias not_allowed)
				(pads allowed)
				(copperpour not_allowed)
				(footprints allowed)
			)
			(placement
				(enabled no)
				(sheetname "")
			)
			(fill
				(thermal_gap 0.5)
				(thermal_bridge_width 0.5)
				(island_removal_mode 0)
			)
			(polygon
				(pts
					(xy 28.5115 -58.166) (xy 28.0035 -58.166) (xy 28.0035 -57.404) (xy 28.5115 -57.404)
				)
			)
		)
		(zone
			(layer "F.Cu")
			(hatch none 0.5)
			(connect_pads
				(clearance 0)
			)
			(min_thickness 0.25)
			(keepout
				(tracks not_allowed)
				(vias allowed)
				(pads allowed)
				(copperpour not_allowed)
				(footprints allowed)
			)
			(placement
				(enabled no)
				(sheetname "")
			)
			(fill
				(thermal_gap 0.5)
				(thermal_bridge_width 0.5)
				(island_removal_mode 0)
			)
			(polygon
				(pts
					(xy 28.5115 -57.404) (xy 28.5115 -58.166) (xy 28.0035 -58.166) (xy 28.0035 -57.404)
				)
			)
		)
	)
	(footprint ""
		(layer "F.Cu")
		(at 178.054 -81.026 180)
		(property "Reference" "R4D18"
			(at 0 0 180)
			(layer "F.SilkS")
			(hide yes)
			(effects
				(font
					(size 1.27 1.27)
				)
			)
		)
		(property "Value" ""
			(at 0 0 180)
			(layer "F.Fab")
			(effects
				(font
					(size 1.27 1.27)
				)
			)
		)
		(duplicate_pad_numbers_are_jumpers no)
		(fp_poly
			(pts
				(xy -0.2794 -0.1016) (xy 0.2794 -0.1016) (xy 0.2794 0.9906) (xy -0.2794 0.9906)
			)
			(stroke
				(width 0)
				(type default)
			)
			(fill no)
			(layer "F.CrtYd")
		)
		(fp_line
			(start 0.2794 0.9906)
			(end 0.2794 -0.1016)
			(stroke
				(width 0.1)
				(type default)
			)
			(layer "F.Fab")
		)
		(fp_line
			(start 0.2794 -0.1016)
			(end -0.2794 -0.1016)
			(stroke
				(width 0.1)
				(type default)
			)
			(layer "F.Fab")
		)
		(fp_line
			(start -0.2794 0.9906)
			(end 0.2794 0.9906)
			(stroke
				(width 0.1)
				(type default)
			)
			(layer "F.Fab")
		)
		(fp_line
			(start -0.2794 -0.1016)
			(end -0.2794 0.9906)
			(stroke
				(width 0.1)
				(type default)
			)
			(layer "F.Fab")
		)
		(pad "1" smd rect
			(at 0 0 180)
			(size 0.508 0.508)
			(layers "F.Cu" "F.Mask" "F.Paste")
			(net "CLK_100M_CPU0_BCLK1_DN")
		)
		(pad "2" smd rect
			(at 0 0.889 180)
			(size 0.508 0.508)
			(layers "F.Cu" "F.Mask" "F.Paste")
			(net "GND")
		)
		(zone
			(layer "F.Cu")
			(hatch none 0.5)
			(connect_pads
				(clearance 0)
			)
			(min_thickness 0.25)
			(keepout
				(tracks not_allowed)
				(vias allowed)
				(pads allowed)
				(copperpour not_allowed)
				(footprints allowed)
			)
			(placement
				(enabled no)
				(sheetname "")
			)
			(fill
				(thermal_gap 0.5)
				(thermal_bridge_width 0.5)
				(island_removal_mode 0)
			)
			(polygon
				(pts
					(xy 178.308 -81.661) (xy 177.8 -81.661) (xy 177.8 -81.28) (xy 178.308 -81.28)
				)
			)
		)
		(zone
			(layer "F.Cu")
			(hatch none 0.5)
			(connect_pads
				(clearance 0)
			)
			(min_thickness 0.25)
			(keepout
				(tracks allowed)
				(vias not_allowed)
				(pads allowed)
				(copperpour not_allowed)
				(footprints allowed)
			)
			(placement
				(enabled no)
				(sheetname "")
			)
			(fill
				(thermal_gap 0.5)
				(thermal_bridge_width 0.5)
				(island_removal_mode 0)
			)
			(polygon
				(pts
					(xy 178.308 -81.28) (xy 177.8 -81.28) (xy 177.8 -81.661) (xy 178.308 -81.661)
				)
			)
		)
	)
	(footprint ""
		(layer "F.Cu")
		(at 171.6532 -7.8232 90)
		(property "Reference" "C4G7"
			(at 0 0 90)
			(layer "F.SilkS")
			(hide yes)
			(effects
				(font
					(size 1.27 1.27)
				)
			)
		)
		(property "Value" ""
			(at 0 0 90)
			(layer "F.Fab")
			(effects
				(font
					(size 1.27 1.27)
				)
			)
		)
		(duplicate_pad_numbers_are_jumpers no)
		(fp_rect
			(start 0.3048 0.9906)
			(end -0.3048 -0.1016)
			(stroke
				(width 0)
				(type default)
			)
			(fill no)
			(layer "F.CrtYd")
		)
		(fp_line
			(start 0.3048 -0.1016)
			(end -0.3048 -0.1016)
			(stroke
				(width 0.1)
				(type default)
			)
			(layer "F.Fab")
		)
		(fp_line
			(start -0.3048 -0.1016)
			(end -0.3048 0.9906)
			(stroke
				(width 0.1)
				(type default)
			)
			(layer "F.Fab")
		)
		(fp_line
			(start 0.3048 0.9906)
			(end 0.3048 -0.1016)
			(stroke
				(width 0.1)
				(type default)
			)
			(layer "F.Fab")
		)
		(fp_line
			(start -0.3048 0.9906)
			(end 0.3048 0.9906)
			(stroke
				(width 0.1)
				(type default)
			)
			(layer "F.Fab")
		)
		(pad "1" smd rect
			(at 0 0 90)
			(size 0.508 0.508)
			(layers "F.Cu" "F.Mask" "F.Paste")
			(net "FM_PVPP_CPU1_EN")
		)
		(pad "2" smd rect
			(at 0 0.889 90)
			(size 0.508 0.508)
			(layers "F.Cu" "F.Mask" "F.Paste")
			(net "AGND_PVPP_GHJ")
		)
		(zone
			(layer "F.Cu")
			(hatch none 0.5)
			(connect_pads
				(clearance 0)
			)
			(min_thickness 0.25)
			(keepout
				(tracks not_allowed)
				(vias allowed)
				(pads allowed)
				(copperpour not_allowed)
				(footprints allowed)
			)
			(placement
				(enabled no)
				(sheetname "")
			)
			(fill
				(thermal_gap 0.5)
				(thermal_bridge_width 0.5)
				(island_removal_mode 0)
			)
			(polygon
				(pts
					(xy 172.2882 -8.0772) (xy 171.9072 -8.0772) (xy 171.9072 -7.5692) (xy 172.2882 -7.5692)
				)
			)
		)
		(zone
			(layer "F.Cu")
			(hatch none 0.5)
			(connect_pads
				(clearance 0)
			)
			(min_thickness 0.25)
			(keepout
				(tracks allowed)
				(vias not_allowed)
				(pads allowed)
				(copperpour not_allowed)
				(footprints allowed)
			)
			(placement
				(enabled no)
				(sheetname "")
			)
			(fill
				(thermal_gap 0.5)
				(thermal_bridge_width 0.5)
				(island_removal_mode 0)
			)
			(polygon
				(pts
					(xy 172.2882 -8.0772) (xy 171.9072 -8.0772) (xy 171.9072 -7.5692) (xy 172.2882 -7.5692)
				)
			)
		)
	)
	(footprint ""
		(layer "F.Cu")
		(at 421.627046 -48.968152)
		(property "Reference" "R25W103"
			(at -0.8382 -0.67818 0)
			(unlocked yes)
			(layer "F.SilkS")
			(effects
				(font
					(size 0.4064 0.254)
					(thickness 0.1524)
				)
				(justify left)
			)
		)
		(property "Value" ""
			(at 0 0 0)
			(layer "F.Fab")
			(effects
				(font
					(size 1.27 1.27)
				)
			)
		)
		(duplicate_pad_numbers_are_jumpers no)
		(fp_poly
			(pts
				(xy -0.2794 -0.1016) (xy 0.2794 -0.1016) (xy 0.2794 0.9906) (xy -0.2794 0.9906)
			)
			(stroke
				(width 0)
				(type default)
			)
			(fill no)
			(layer "F.CrtYd")
		)
		(fp_line
			(start -0.2794 -0.1016)
			(end -0.2794 0.9906)
			(stroke
				(width 0.1)
				(type default)
			)
			(layer "F.Fab")
		)
		(fp_line
			(start -0.2794 0.9906)
			(end 0.2794 0.9906)
			(stroke
				(width 0.1)
				(type default)
			)
			(layer "F.Fab")
		)
		(fp_line
			(start 0.2794 -0.1016)
			(end -0.2794 -0.1016)
			(stroke
				(width 0.1)
				(type default)
			)
			(layer "F.Fab")
		)
		(fp_line
			(start 0.2794 0.9906)
			(end 0.2794 -0.1016)
			(stroke
				(width 0.1)
				(type default)
			)
			(layer "F.Fab")
		)
		(pad "1" smd rect
			(at 0 0)
			(size 0.508 0.508)
			(layers "F.Cu" "F.Mask" "F.Paste")
			(net "P3V3_STBY")
		)
		(pad "2" smd rect
			(at 0 0.889)
			(size 0.508 0.508)
			(layers "F.Cu" "F.Mask" "F.Paste")
			(net "BMC_STRAP_BIT20")
		)
		(zone
			(layer "F.Cu")
			(hatch none 0.5)
			(connect_pads
				(clearance 0)
			)
			(min_thickness 0.25)
			(keepout
				(tracks allowed)
				(vias not_allowed)
				(pads allowed)
				(copperpour not_allowed)
				(footprints allowed)
			)
			(placement
				(enabled no)
				(sheetname "")
			)
			(fill
				(thermal_gap 0.5)
				(thermal_bridge_width 0.5)
				(island_removal_mode 0)
			)
			(polygon
				(pts
					(xy 421.373046 -48.714152) (xy 421.881046 -48.714152) (xy 421.881046 -48.333152) (xy 421.373046 -48.333152)
				)
			)
		)
		(zone
			(layer "F.Cu")
			(hatch none 0.5)
			(connect_pads
				(clearance 0)
			)
			(min_thickness 0.25)
			(keepout
				(tracks not_allowed)
				(vias allowed)
				(pads allowed)
				(copperpour not_allowed)
				(footprints allowed)
			)
			(placement
				(enabled no)
				(sheetname "")
			)
			(fill
				(thermal_gap 0.5)
				(thermal_bridge_width 0.5)
				(island_removal_mode 0)
			)
			(polygon
				(pts
					(xy 421.373046 -48.333152) (xy 421.881046 -48.333152) (xy 421.881046 -48.714152) (xy 421.373046 -48.714152)
				)
			)
		)
	)
	(footprint ""
		(layer "F.Cu")
		(at 372.491 -154.4955)
		(property "Reference" "C7A8"
			(at 0 0 0)
			(layer "F.SilkS")
			(hide yes)
			(effects
				(font
					(size 1.27 1.27)
				)
			)
		)
		(property "Value" ""
			(at 0 0 0)
			(layer "F.Fab")
			(effects
				(font
					(size 1.27 1.27)
				)
			)
		)
		(duplicate_pad_numbers_are_jumpers no)
		(fp_poly
			(pts
				(xy 0.3048 -0.1016) (xy 0.3048 0.9906) (xy -0.3048 0.9906) (xy -0.3048 -0.1016)
			)
			(stroke
				(width 0)
				(type default)
			)
			(fill no)
			(layer "F.CrtYd")
		)
		(fp_line
			(start -0.3048 -0.1016)
			(end -0.3048 0.9906)
			(stroke
				(width 0.1)
				(type default)
			)
			(layer "F.Fab")
		)
		(fp_line
			(start -0.3048 0.9906)
			(end 0.3048 0.9906)
			(stroke
				(width 0.1)
				(type default)
			)
			(layer "F.Fab")
		)
		(fp_line
			(start 0.3048 -0.1016)
			(end -0.3048 -0.1016)
			(stroke
				(width 0.1)
				(type default)
			)
			(layer "F.Fab")
		)
		(fp_line
			(start 0.3048 0.9906)
			(end 0.3048 -0.1016)
			(stroke
				(width 0.1)
				(type default)
			)
			(layer "F.Fab")
		)
		(pad "1" smd rect
			(at 0 0)
			(size 0.508 0.508)
			(layers "F.Cu" "F.Mask" "F.Paste")
			(net "P5V_STBY")
		)
		(pad "2" smd rect
			(at 0 0.889)
			(size 0.508 0.508)
			(layers "F.Cu" "F.Mask" "F.Paste")
			(net "GND")
		)
		(zone
			(layer "F.Cu")
			(hatch none 0.5)
			(connect_pads
				(clearance 0)
			)
			(min_thickness 0.25)
			(keepout
				(tracks allowed)
				(vias not_allowed)
				(pads allowed)
				(copperpour not_allowed)
				(footprints allowed)
			)
			(placement
				(enabled no)
				(sheetname "")
			)
			(fill
				(thermal_gap 0.5)
				(thermal_bridge_width 0.5)
				(island_removal_mode 0)
			)
			(polygon
				(pts
					(xy 372.237 -154.2415) (xy 372.745 -154.2415) (xy 372.745 -153.8605) (xy 372.237 -153.8605)
				)
			)
		)
		(zone
			(layer "F.Cu")
			(hatch none 0.5)
			(connect_pads
				(clearance 0)
			)
			(min_thickness 0.25)
			(keepout
				(tracks not_allowed)
				(vias allowed)
				(pads allowed)
				(copperpour not_allowed)
				(footprints allowed)
			)
			(placement
				(enabled no)
				(sheetname "")
			)
			(fill
				(thermal_gap 0.5)
				(thermal_bridge_width 0.5)
				(island_removal_mode 0)
			)
			(polygon
				(pts
					(xy 372.237 -153.8605) (xy 372.745 -153.8605) (xy 372.745 -154.2415) (xy 372.237 -154.2415)
				)
			)
		)
	)
	(footprint ""
		(layer "F.Cu")
		(at 406.9461 -64.897 90)
		(property "Reference" "R8E10"
			(at 0 0 90)
			(layer "F.SilkS")
			(hide yes)
			(effects
				(font
					(size 1.27 1.27)
				)
			)
		)
		(property "Value" ""
			(at 0 0 90)
			(layer "F.Fab")
			(effects
				(font
					(size 1.27 1.27)
				)
			)
		)
		(duplicate_pad_numbers_are_jumpers no)
		(fp_poly
			(pts
				(xy -0.2794 -0.1016) (xy 0.2794 -0.1016) (xy 0.2794 0.9906) (xy -0.2794 0.9906)
			)
			(stroke
				(width 0)
				(type default)
			)
			(fill no)
			(layer "F.CrtYd")
		)
		(pad "1" smd rect
			(at 0 0 90)
			(size 0.508 0.508)
			(layers "F.Cu" "F.Mask" "F.Paste")
			(net "SPI_PCH_MOSI")
		)
		(pad "2" smd rect
			(at 0 0.889 90)
			(size 0.508 0.508)
			(layers "F.Cu" "F.Mask" "F.Paste")
			(net "SPI_PCH_TPM_MOSI_R")
		)
		(zone
			(layer "F.Cu")
			(hatch none 0.5)
			(connect_pads
				(clearance 0)
			)
			(min_thickness 0.25)
			(keepout
				(tracks allowed)
				(vias not_allowed)
				(pads allowed)
				(copperpour not_allowed)
				(footprints allowed)
			)
			(placement
				(enabled no)
				(sheetname "")
			)
			(fill
				(thermal_gap 0.5)
				(thermal_bridge_width 0.5)
				(island_removal_mode 0)
			)
			(polygon
				(pts
					(xy 407.2001 -64.643) (xy 407.2001 -65.151) (xy 407.5811 -65.151) (xy 407.5811 -64.643)
				)
			)
		)
		(zone
			(layer "F.Cu")
			(hatch none 0.5)
			(connect_pads
				(clearance 0)
			)
			(min_thickness 0.25)
			(keepout
				(tracks not_allowed)
				(vias allowed)
				(pads allowed)
				(copperpour not_allowed)
				(footprints allowed)
			)
			(placement
				(enabled no)
				(sheetname "")
			)
			(fill
				(thermal_gap 0.5)
				(thermal_bridge_width 0.5)
				(island_removal_mode 0)
			)
			(polygon
				(pts
					(xy 407.5811 -64.643) (xy 407.5811 -65.151) (xy 407.2001 -65.151) (xy 407.2001 -64.643)
				)
			)
		)
	)
	(footprint ""
		(layer "F.Cu")
		(at 13.716 -97.028 180)
		(property "Reference" "C1C13"
			(at 0 0 180)
			(layer "F.SilkS")
			(hide yes)
			(effects
				(font
					(size 1.27 1.27)
				)
			)
		)
		(property "Value" ""
			(at 0 0 180)
			(layer "F.Fab")
			(effects
				(font
					(size 1.27 1.27)
				)
			)
		)
		(duplicate_pad_numbers_are_jumpers no)
		(fp_rect
			(start 0.3048 -0.1016)
			(end -0.3048 0.9906)
			(stroke
				(width 0)
				(type default)
			)
			(fill no)
			(layer "F.CrtYd")
		)
		(fp_line
			(start 0.3048 0.9906)
			(end 0.3048 -0.1016)
			(stroke
				(width 0.1)
				(type default)
			)
			(layer "F.Fab")
		)
		(fp_line
			(start 0.3048 -0.1016)
			(end -0.3048 -0.1016)
			(stroke
				(width 0.1)
				(type default)
			)
			(layer "F.Fab")
		)
		(fp_line
			(start -0.3048 0.9906)
			(end 0.3048 0.9906)
			(stroke
				(width 0.1)
				(type default)
			)
			(layer "F.Fab")
		)
		(fp_line
			(start -0.3048 -0.1016)
			(end -0.3048 0.9906)
			(stroke
				(width 0.1)
				(type default)
			)
			(layer "F.Fab")
		)
		(pad "1" smd rect
			(at 0 0 180)
			(size 0.508 0.508)
			(layers "F.Cu" "F.Mask" "F.Paste")
			(net "VR_PVCCIN_CPU1_VD12")
		)
		(pad "2" smd rect
			(at 0 0.889 180)
			(size 0.508 0.508)
			(layers "F.Cu" "F.Mask" "F.Paste")
			(net "GND")
		)
		(zone
			(layer "F.Cu")
			(hatch none 0.5)
			(connect_pads
				(clearance 0)
			)
			(min_thickness 0.25)
			(keepout
				(tracks allowed)
				(vias not_allowed)
				(pads allowed)
				(copperpour not_allowed)
				(footprints allowed)
			)
			(placement
				(enabled no)
				(sheetname "")
			)
			(fill
				(thermal_gap 0.5)
				(thermal_bridge_width 0.5)
				(island_removal_mode 0)
			)
			(polygon
				(pts
					(xy 13.462 -97.282) (xy 13.97 -97.282) (xy 13.97 -97.663) (xy 13.462 -97.663)
				)
			)
		)
		(zone
			(layer "F.Cu")
			(hatch none 0.5)
			(connect_pads
				(clearance 0)
			)
			(min_thickness 0.25)
			(keepout
				(tracks not_allowed)
				(vias allowed)
				(pads allowed)
				(copperpour not_allowed)
				(footprints allowed)
			)
			(placement
				(enabled no)
				(sheetname "")
			)
			(fill
				(thermal_gap 0.5)
				(thermal_bridge_width 0.5)
				(island_removal_mode 0)
			)
			(polygon
				(pts
					(xy 13.462 -97.282) (xy 13.97 -97.282) (xy 13.97 -97.663) (xy 13.462 -97.663)
				)
			)
		)
	)
)
